(kicad_pcb
	(version 20260206)
	(generator "pcbnew")
	(generator_version "10.0")
	(general
		(thickness 1.6)
		(legacy_teardrops no)
	)
	(paper "A4")
	(title_block
		(title "Wiwynn_Tioga_Pass_MB.brd")
		(comment 1 "Tioga Pass / footprints 4024-4030 of 4770")
	)
	(layers
		(0 "F.Cu" signal "TOP")
		(4 "In1.Cu" signal "L2GND")
		(6 "In2.Cu" signal "L3")
		(8 "In3.Cu" signal "L4GND")
		(10 "In4.Cu" signal "L5")
		(12 "In5.Cu" signal "L6GND")
		(14 "In6.Cu" signal "L7VCC")
		(16 "In7.Cu" signal "L8VCC")
		(18 "In8.Cu" signal "L9GND")
		(20 "In9.Cu" signal "L10")
		(22 "In10.Cu" signal "L11GND")
		(24 "In11.Cu" signal "L12")
		(26 "In12.Cu" signal "L13GND")
		(2 "B.Cu" signal "BOTTOM")
		(9 "F.Adhes" user "F.Adhesive")
		(11 "B.Adhes" user "B.Adhesive")
		(13 "F.Paste" user "Package Geometry/Pastemask Top")
		(15 "B.Paste" user "Package Geometry/Pastemask Bottom")
		(5 "F.SilkS" user "Ref Des/Silkscreen Top")
		(7 "B.SilkS" user "Ref Des/Silkscreen Bottom")
		(1 "F.Mask" user "Board Geometry/Soldermask Top")
		(3 "B.Mask" user "Board Geometry/Soldermask Bottom")
		(17 "Dwgs.User" user "User.Drawings")
		(19 "Cmts.User" user "User.Comments")
		(21 "Eco1.User" user "User.Eco1")
		(23 "Eco2.User" user "User.Eco2")
		(25 "Edge.Cuts" user "Board Geometry/Outline")
		(27 "Margin" user)
		(31 "F.CrtYd" user "Package Geometry/Place Bound Top")
		(29 "B.CrtYd" user "Package Geometry/Place Bound Bottom")
		(35 "F.Fab" user "Ref Des/Assembly Top")
		(33 "B.Fab" user "Ref Des/Assembly Bottom")
	)
	(footprint ""
		(layer "B.Cu")
		(at 13.10894 -97.11436 90)
		(property "Reference" "C9N18"
			(at 0 0 90)
			(layer "B.SilkS")
			(hide yes)
			(effects
				(font
					(size 1.27 1.27)
				)
				(justify mirror)
			)
		)
		(property "Value" ""
			(at 0 0 90)
			(layer "B.Fab")
			(effects
				(font
					(size 1.27 1.27)
				)
				(justify mirror)
			)
		)
		(duplicate_pad_numbers_are_jumpers no)
		(fp_poly
			(pts
				(xy -0.3048 -0.1016) (xy -0.3048 0.9906) (xy 0.3048 0.9906) (xy 0.3048 -0.1016)
			)
			(stroke
				(width 0)
				(type default)
			)
			(fill no)
			(layer "B.CrtYd")
		)
		(fp_line
			(start 0.3048 -0.1016)
			(end 0.3048 0.9906)
			(stroke
				(width 0.1)
				(type default)
			)
			(layer "B.Fab")
		)
		(fp_line
			(start -0.3048 -0.1016)
			(end 0.3048 -0.1016)
			(stroke
				(width 0.1)
				(type default)
			)
			(layer "B.Fab")
		)
		(fp_line
			(start 0.3048 0.9906)
			(end -0.3048 0.9906)
			(stroke
				(width 0.1)
				(type default)
			)
			(layer "B.Fab")
		)
		(fp_line
			(start -0.3048 0.9906)
			(end -0.3048 -0.1016)
			(stroke
				(width 0.1)
				(type default)
			)
			(layer "B.Fab")
		)
		(pad "1" smd rect
			(at 0 0 270)
			(size 0.508 0.508)
			(layers "B.Cu" "B.Mask" "B.Paste")
			(net "P3E_CPU1_PE3_MP_C_TXN<8>")
		)
		(pad "2" smd rect
			(at 0 0.889 270)
			(size 0.508 0.508)
			(layers "B.Cu" "B.Mask" "B.Paste")
			(net "P3E_CPU1_PE3_MP_TXN<8>")
		)
		(zone
			(layer "B.Cu")
			(hatch none 0.5)
			(connect_pads
				(clearance 0)
			)
			(min_thickness 0.25)
			(keepout
				(tracks allowed)
				(vias not_allowed)
				(pads allowed)
				(copperpour not_allowed)
				(footprints allowed)
			)
			(placement
				(enabled no)
				(sheetname "")
			)
			(fill
				(thermal_gap 0.5)
				(thermal_bridge_width 0.5)
				(island_removal_mode 0)
			)
			(polygon
				(pts
					(xy 13.36294 -97.36836) (xy 13.36294 -96.86036) (xy 13.74394 -96.86036) (xy 13.74394 -97.36836)
				)
			)
		)
		(zone
			(layer "B.Cu")
			(hatch none 0.5)
			(connect_pads
				(clearance 0)
			)
			(min_thickness 0.25)
			(keepout
				(tracks not_allowed)
				(vias allowed)
				(pads allowed)
				(copperpour not_allowed)
				(footprints allowed)
			)
			(placement
				(enabled no)
				(sheetname "")
			)
			(fill
				(thermal_gap 0.5)
				(thermal_bridge_width 0.5)
				(island_removal_mode 0)
			)
			(polygon
				(pts
					(xy 13.74394 -97.36836) (xy 13.74394 -96.86036) (xy 13.36294 -96.86036) (xy 13.36294 -97.36836)
				)
			)
		)
	)
	(footprint ""
		(layer "B.Cu")
		(at 379.6792 -137.2108)
		(property "Reference" "C3M19"
			(at 0 0 0)
			(layer "B.SilkS")
			(hide yes)
			(effects
				(font
					(size 1.27 1.27)
				)
				(justify mirror)
			)
		)
		(property "Value" ""
			(at 0 0 0)
			(layer "B.Fab")
			(effects
				(font
					(size 1.27 1.27)
				)
				(justify mirror)
			)
		)
		(duplicate_pad_numbers_are_jumpers no)
		(fp_poly
			(pts
				(xy -0.3048 -0.1016) (xy -0.3048 0.9906) (xy 0.3048 0.9906) (xy 0.3048 -0.1016)
			)
			(stroke
				(width 0)
				(type default)
			)
			(fill no)
			(layer "B.CrtYd")
		)
		(fp_line
			(start -0.3048 -0.1016)
			(end 0.3048 -0.1016)
			(stroke
				(width 0.1)
				(type default)
			)
			(layer "B.Fab")
		)
		(fp_line
			(start -0.3048 0.9906)
			(end -0.3048 -0.1016)
			(stroke
				(width 0.1)
				(type default)
			)
			(layer "B.Fab")
		)
		(fp_line
			(start 0.3048 -0.1016)
			(end 0.3048 0.9906)
			(stroke
				(width 0.1)
				(type default)
			)
			(layer "B.Fab")
		)
		(fp_line
			(start 0.3048 0.9906)
			(end -0.3048 0.9906)
			(stroke
				(width 0.1)
				(type default)
			)
			(layer "B.Fab")
		)
		(pad "1" smd rect
			(at 0 0 180)
			(size 0.508 0.508)
			(layers "B.Cu" "B.Mask" "B.Paste")
			(net "P1V05_PCH_STBY_VCCA_PLL1")
		)
		(pad "2" smd rect
			(at 0 0.889 180)
			(size 0.508 0.508)
			(layers "B.Cu" "B.Mask" "B.Paste")
			(net "GND")
		)
		(zone
			(layer "B.Cu")
			(hatch none 0.5)
			(connect_pads
				(clearance 0)
			)
			(min_thickness 0.25)
			(keepout
				(tracks allowed)
				(vias not_allowed)
				(pads allowed)
				(copperpour not_allowed)
				(footprints allowed)
			)
			(placement
				(enabled no)
				(sheetname "")
			)
			(fill
				(thermal_gap 0.5)
				(thermal_bridge_width 0.5)
				(island_removal_mode 0)
			)
			(polygon
				(pts
					(xy 379.9332 -136.9568) (xy 379.4252 -136.9568) (xy 379.4252 -136.5758) (xy 379.9332 -136.5758)
				)
			)
		)
		(zone
			(layer "B.Cu")
			(hatch none 0.5)
			(connect_pads
				(clearance 0)
			)
			(min_thickness 0.25)
			(keepout
				(tracks not_allowed)
				(vias allowed)
				(pads allowed)
				(copperpour not_allowed)
				(footprints allowed)
			)
			(placement
				(enabled no)
				(sheetname "")
			)
			(fill
				(thermal_gap 0.5)
				(thermal_bridge_width 0.5)
				(island_removal_mode 0)
			)
			(polygon
				(pts
					(xy 379.9332 -136.5758) (xy 379.4252 -136.5758) (xy 379.4252 -136.9568) (xy 379.9332 -136.9568)
				)
			)
		)
	)
	(footprint ""
		(layer "B.Cu")
		(at 354.460048 -86.93404 180)
		(property "Reference" "SH3P2"
			(at 0 0 0)
			(layer "B.SilkS")
			(hide yes)
			(effects
				(font
					(size 1.27 1.27)
				)
				(justify mirror)
			)
		)
		(property "Value" ""
			(at 0 0 0)
			(layer "B.Fab")
			(effects
				(font
					(size 1.27 1.27)
				)
				(justify mirror)
			)
		)
		(duplicate_pad_numbers_are_jumpers no)
		(fp_poly
			(pts
				(xy 0.1651 -0.0508) (xy 0.1651 0.5842) (xy -0.1651 0.5842) (xy -0.1651 -0.0508)
			)
			(stroke
				(width 0)
				(type default)
			)
			(fill no)
			(layer "B.CrtYd")
		)
		(fp_line
			(start 0.1651 0.5842)
			(end 0.1651 -0.0508)
			(stroke
				(width 0.1)
				(type default)
			)
			(layer "B.Fab")
		)
		(fp_line
			(start 0.1651 -0.0508)
			(end -0.1651 -0.0508)
			(stroke
				(width 0.1)
				(type default)
			)
			(layer "B.Fab")
		)
		(fp_line
			(start -0.1651 0.5842)
			(end 0.1651 0.5842)
			(stroke
				(width 0.1)
				(type default)
			)
			(layer "B.Fab")
		)
		(fp_line
			(start -0.1651 -0.0508)
			(end -0.1651 0.5842)
			(stroke
				(width 0.1)
				(type default)
			)
			(layer "B.Fab")
		)
		(pad "1" smd custom
			(at 0 0 180)
			(size 0.0762 0.0762)
			(layers "B.Cu" "B.Mask" "B.Paste")
			(net "VSENSE_PVCCIO_CPU0_SKT_VRTN")
			(options
				(clearance outline)
				(anchor circle)
			)
			(primitives
				(gr_poly
					(pts
						(arc
							(start -0.1524 0.10795)
							(mid -0.098518 0.130268)
							(end -0.0762 0.18415)
						)
						(xy -0.0762 0.22225) (xy 0.0762 0.22225)
						(arc
							(start 0.0762 0.18415)
							(mid 0.098518 0.130268)
							(end 0.1524 0.10795)
						)
						(xy 0.1524 -0.22225) (xy -0.1524 -0.22225)
					)
					(width 0)
					(fill yes)
				)
			)
		)
		(pad "2" smd custom
			(at 0 0.5334)
			(size 0.0762 0.0762)
			(layers "B.Cu" "B.Mask" "B.Paste")
			(net "VSENSE_PVCCIO_CPU0_AVSN")
			(options
				(clearance outline)
				(anchor circle)
			)
			(primitives
				(gr_poly
					(pts
						(arc
							(start -0.1524 0.10795)
							(mid -0.098518 0.130268)
							(end -0.0762 0.18415)
						)
						(xy -0.0762 0.22225) (xy 0.0762 0.22225)
						(arc
							(start 0.0762 0.18415)
							(mid 0.098518 0.130268)
							(end 0.1524 0.10795)
						)
						(xy 0.1524 -0.22225) (xy -0.1524 -0.22225)
					)
					(width 0)
					(fill yes)
				)
			)
		)
	)
	(footprint ""
		(layer "B.Cu")
		(at 485.8512 -128.2065 180)
		(property "Reference" "R1U19"
			(at 0 0 0)
			(layer "B.SilkS")
			(hide yes)
			(effects
				(font
					(size 1.27 1.27)
				)
				(justify mirror)
			)
		)
		(property "Value" ""
			(at 0 0 0)
			(layer "B.Fab")
			(effects
				(font
					(size 1.27 1.27)
				)
				(justify mirror)
			)
		)
		(duplicate_pad_numbers_are_jumpers no)
		(fp_poly
			(pts
				(xy 0.2794 -0.1016) (xy -0.2794 -0.1016) (xy -0.2794 0.9906) (xy 0.2794 0.9906)
			)
			(stroke
				(width 0)
				(type default)
			)
			(fill no)
			(layer "B.CrtYd")
		)
		(fp_line
			(start 0.2794 0.9906)
			(end -0.2794 0.9906)
			(stroke
				(width 0.1)
				(type default)
			)
			(layer "B.Fab")
		)
		(fp_line
			(start 0.2794 -0.1016)
			(end 0.2794 0.9906)
			(stroke
				(width 0.1)
				(type default)
			)
			(layer "B.Fab")
		)
		(fp_line
			(start -0.2794 0.9906)
			(end -0.2794 -0.1016)
			(stroke
				(width 0.1)
				(type default)
			)
			(layer "B.Fab")
		)
		(fp_line
			(start -0.2794 -0.1016)
			(end 0.2794 -0.1016)
			(stroke
				(width 0.1)
				(type default)
			)
			(layer "B.Fab")
		)
		(pad "1" smd rect
			(at 0 0)
			(size 0.508 0.508)
			(layers "B.Cu" "B.Mask" "B.Paste")
			(net "SMB_SMLINK0_STBY_LVC3_SCL")
		)
		(pad "2" smd rect
			(at 0 0.889)
			(size 0.508 0.508)
			(layers "B.Cu" "B.Mask" "B.Paste")
			(net "SMB_SPRINGVILLE_STBY_LVC3_SCL")
		)
		(zone
			(layer "B.Cu")
			(hatch none 0.5)
			(connect_pads
				(clearance 0)
			)
			(min_thickness 0.25)
			(keepout
				(tracks not_allowed)
				(vias allowed)
				(pads allowed)
				(copperpour not_allowed)
				(footprints allowed)
			)
			(placement
				(enabled no)
				(sheetname "")
			)
			(fill
				(thermal_gap 0.5)
				(thermal_bridge_width 0.5)
				(island_removal_mode 0)
			)
			(polygon
				(pts
					(xy 485.5972 -128.8415) (xy 486.1052 -128.8415) (xy 486.1052 -128.4605) (xy 485.5972 -128.4605)
				)
			)
		)
		(zone
			(layer "B.Cu")
			(hatch none 0.5)
			(connect_pads
				(clearance 0)
			)
			(min_thickness 0.25)
			(keepout
				(tracks allowed)
				(vias not_allowed)
				(pads allowed)
				(copperpour not_allowed)
				(footprints allowed)
			)
			(placement
				(enabled no)
				(sheetname "")
			)
			(fill
				(thermal_gap 0.5)
				(thermal_bridge_width 0.5)
				(island_removal_mode 0)
			)
			(polygon
				(pts
					(xy 485.5972 -128.4605) (xy 486.1052 -128.4605) (xy 486.1052 -128.8415) (xy 485.5972 -128.8415)
				)
			)
		)
	)
	(footprint ""
		(layer "B.Cu")
		(at 295.1226 -65.462404 90)
		(property "Reference" "R4P23"
			(at 0 0 90)
			(layer "B.SilkS")
			(hide yes)
			(effects
				(font
					(size 1.27 1.27)
				)
				(justify mirror)
			)
		)
		(property "Value" ""
			(at 0 0 90)
			(layer "B.Fab")
			(effects
				(font
					(size 1.27 1.27)
				)
				(justify mirror)
			)
		)
		(duplicate_pad_numbers_are_jumpers no)
		(fp_poly
			(pts
				(xy 0.2794 -0.1016) (xy -0.2794 -0.1016) (xy -0.2794 0.9906) (xy 0.2794 0.9906)
			)
			(stroke
				(width 0)
				(type default)
			)
			(fill no)
			(layer "B.CrtYd")
		)
		(fp_line
			(start 0.2794 -0.1016)
			(end 0.2794 0.9906)
			(stroke
				(width 0.1)
				(type default)
			)
			(layer "B.Fab")
		)
		(fp_line
			(start -0.2794 -0.1016)
			(end 0.2794 -0.1016)
			(stroke
				(width 0.1)
				(type default)
			)
			(layer "B.Fab")
		)
		(fp_line
			(start 0.2794 0.9906)
			(end -0.2794 0.9906)
			(stroke
				(width 0.1)
				(type default)
			)
			(layer "B.Fab")
		)
		(fp_line
			(start -0.2794 0.9906)
			(end -0.2794 -0.1016)
			(stroke
				(width 0.1)
				(type default)
			)
			(layer "B.Fab")
		)
		(pad "1" smd rect
			(at 0 0 270)
			(size 0.508 0.508)
			(layers "B.Cu" "B.Mask" "B.Paste")
			(net "PVCCIO_CPU0")
		)
		(pad "2" smd rect
			(at 0 0.889 270)
			(size 0.508 0.508)
			(layers "B.Cu" "B.Mask" "B.Paste")
			(net "XDP_CPU0_TDO")
		)
		(zone
			(layer "B.Cu")
			(hatch none 0.5)
			(connect_pads
				(clearance 0)
			)
			(min_thickness 0.25)
			(keepout
				(tracks allowed)
				(vias not_allowed)
				(pads allowed)
				(copperpour not_allowed)
				(footprints allowed)
			)
			(placement
				(enabled no)
				(sheetname "")
			)
			(fill
				(thermal_gap 0.5)
				(thermal_bridge_width 0.5)
				(island_removal_mode 0)
			)
			(polygon
				(pts
					(xy 295.3766 -65.716404) (xy 295.3766 -65.208404) (xy 295.7576 -65.208404) (xy 295.7576 -65.716404)
				)
			)
		)
		(zone
			(layer "B.Cu")
			(hatch none 0.5)
			(connect_pads
				(clearance 0)
			)
			(min_thickness 0.25)
			(keepout
				(tracks not_allowed)
				(vias allowed)
				(pads allowed)
				(copperpour not_allowed)
				(footprints allowed)
			)
			(placement
				(enabled no)
				(sheetname "")
			)
			(fill
				(thermal_gap 0.5)
				(thermal_bridge_width 0.5)
				(island_removal_mode 0)
			)
			(polygon
				(pts
					(xy 295.7576 -65.716404) (xy 295.7576 -65.208404) (xy 295.3766 -65.208404) (xy 295.3766 -65.716404)
				)
			)
		)
	)
	(footprint ""
		(layer "B.Cu")
		(at 488.442 -113.2332 90)
		(property "Reference" "C1M22"
			(at 0 0 90)
			(layer "B.SilkS")
			(hide yes)
			(effects
				(font
					(size 1.27 1.27)
				)
				(justify mirror)
			)
		)
		(property "Value" ""
			(at 0 0 90)
			(layer "B.Fab")
			(effects
				(font
					(size 1.27 1.27)
				)
				(justify mirror)
			)
		)
		(duplicate_pad_numbers_are_jumpers no)
		(fp_rect
			(start -0.3048 -0.1016)
			(end 0.3048 0.9906)
			(stroke
				(width 0)
				(type default)
			)
			(fill no)
			(layer "B.CrtYd")
		)
		(fp_line
			(start 0.3048 -0.1016)
			(end 0.3048 0.9906)
			(stroke
				(width 0.1)
				(type default)
			)
			(layer "B.Fab")
		)
		(fp_line
			(start -0.3048 -0.1016)
			(end 0.3048 -0.1016)
			(stroke
				(width 0.1)
				(type default)
			)
			(layer "B.Fab")
		)
		(fp_line
			(start 0.3048 0.9906)
			(end -0.3048 0.9906)
			(stroke
				(width 0.1)
				(type default)
			)
			(layer "B.Fab")
		)
		(fp_line
			(start -0.3048 0.9906)
			(end -0.3048 -0.1016)
			(stroke
				(width 0.1)
				(type default)
			)
			(layer "B.Fab")
		)
		(pad "1" smd rect
			(at 0 0 270)
			(size 0.508 0.508)
			(layers "B.Cu" "B.Mask" "B.Paste")
			(net "P12V_STBY")
		)
		(pad "2" smd rect
			(at 0 0.889 270)
			(size 0.508 0.508)
			(layers "B.Cu" "B.Mask" "B.Paste")
			(net "GND")
		)
		(zone
			(layer "B.Cu")
			(hatch none 0.5)
			(connect_pads
				(clearance 0)
			)
			(min_thickness 0.25)
			(keepout
				(tracks allowed)
				(vias not_allowed)
				(pads allowed)
				(copperpour not_allowed)
				(footprints allowed)
			)
			(placement
				(enabled no)
				(sheetname "")
			)
			(fill
				(thermal_gap 0.5)
				(thermal_bridge_width 0.5)
				(island_removal_mode 0)
			)
			(polygon
				(pts
					(xy 488.696 -112.9792) (xy 489.077 -112.9792) (xy 489.077 -113.4872) (xy 488.696 -113.4872)
				)
			)
		)
		(zone
			(layer "B.Cu")
			(hatch none 0.5)
			(connect_pads
				(clearance 0)
			)
			(min_thickness 0.25)
			(keepout
				(tracks not_allowed)
				(vias allowed)
				(pads allowed)
				(copperpour not_allowed)
				(footprints allowed)
			)
			(placement
				(enabled no)
				(sheetname "")
			)
			(fill
				(thermal_gap 0.5)
				(thermal_bridge_width 0.5)
				(island_removal_mode 0)
			)
			(polygon
				(pts
					(xy 488.696 -112.9792) (xy 489.077 -112.9792) (xy 489.077 -113.4872) (xy 488.696 -113.4872)
				)
			)
		)
	)
	(footprint ""
		(layer "B.Cu")
		(at 214.503 -78.4098)
		(property "Reference" "C6P16"
			(at 0 0 0)
			(layer "B.SilkS")
			(hide yes)
			(effects
				(font
					(size 1.27 1.27)
				)
				(justify mirror)
			)
		)
		(property "Value" ""
			(at 0 0 0)
			(layer "B.Fab")
			(effects
				(font
					(size 1.27 1.27)
				)
				(justify mirror)
			)
		)
		(duplicate_pad_numbers_are_jumpers no)
		(fp_poly
			(pts
				(xy 0.4953 -0.2032) (xy -0.4953 -0.2032) (xy -0.4953 1.6002) (xy 0.4953 1.6002)
			)
			(stroke
				(width 0)
				(type default)
			)
			(fill no)
			(layer "B.CrtYd")
		)
		(fp_line
			(start -0.4953 -0.2032)
			(end -0.4953 1.6002)
			(stroke
				(width 0.1)
				(type default)
			)
			(layer "B.Fab")
		)
		(fp_line
			(start -0.4953 1.6002)
			(end 0.4953 1.6002)
			(stroke
				(width 0.1)
				(type default)
			)
			(layer "B.Fab")
		)
		(fp_line
			(start 0.4953 -0.2032)
			(end -0.4953 -0.2032)
			(stroke
				(width 0.1)
				(type default)
			)
			(layer "B.Fab")
		)
		(fp_line
			(start 0.4953 1.6002)
			(end 0.4953 -0.2032)
			(stroke
				(width 0.1)
				(type default)
			)
			(layer "B.Fab")
		)
		(pad "1" smd rect
			(at 0 0 180)
			(size 0.762 0.889)
			(layers "B.Cu" "B.Mask" "B.Paste")
			(net "PVCCIN_CPU0")
		)
		(pad "2" smd rect
			(at 0 1.397 180)
			(size 0.762 0.889)
			(layers "B.Cu" "B.Mask" "B.Paste")
			(net "GND")
		)
		(zone
			(layer "B.Cu")
			(hatch none 0.5)
			(connect_pads
				(clearance 0)
			)
			(min_thickness 0.25)
			(keepout
				(tracks not_allowed)
				(vias allowed)
				(pads allowed)
				(copperpour not_allowed)
				(footprints allowed)
			)
			(placement
				(enabled no)
				(sheetname "")
			)
			(fill
				(thermal_gap 0.5)
				(thermal_bridge_width 0.5)
				(island_removal_mode 0)
			)
			(polygon
				(pts
					(xy 214.884 -77.9653) (xy 214.122 -77.9653) (xy 214.122 -77.4573) (xy 214.884 -77.4573)
				)
			)
		)
	)
)
